(kicad_pcb
	(version 20260206)
	(generator "pcbnew")
	(generator_version "10.0")
	(general
		(thickness 1.6)
		(legacy_teardrops no)
	)
	(paper "A4")
	(title_block
		(title "01162023_DA0F0TEBIF0_F0T_Expander_BD_F_brd_V02_OCP.brd")
		(comment 1 "Grand Teton / footprints 9624-9630 of 9728")
	)
	(layers
		(0 "F.Cu" signal "TOP")
		(4 "In1.Cu" signal "GND")
		(6 "In2.Cu" signal "VCC")
		(8 "In3.Cu" signal "VCC1")
		(10 "In4.Cu" signal "GND1")
		(12 "In5.Cu" signal "IN1")
		(14 "In6.Cu" signal "GND2")
		(16 "In7.Cu" signal "IN2")
		(18 "In8.Cu" signal "GND3")
		(20 "In9.Cu" signal "IN3")
		(22 "In10.Cu" signal "GND4")
		(24 "In11.Cu" signal "IN4")
		(26 "In12.Cu" signal "GND5")
		(28 "In13.Cu" signal "IN5")
		(30 "In14.Cu" signal "GND6")
		(32 "In15.Cu" signal "IN6")
		(34 "In16.Cu" signal "GND7")
		(2 "B.Cu" signal "BOTTOM")
		(9 "F.Adhes" user "F.Adhesive")
		(11 "B.Adhes" user "B.Adhesive")
		(13 "F.Paste" user "Package Geometry/Pastemask Top")
		(15 "B.Paste" user "Package Geometry/Pastemask Bottom")
		(5 "F.SilkS" user "Ref Des/Silkscreen Top")
		(7 "B.SilkS" user "Ref Des/Silkscreen Bottom")
		(1 "F.Mask" user "Board Geometry/Soldermask Top")
		(3 "B.Mask" user "Board Geometry/Soldermask Bottom")
		(17 "Dwgs.User" user "User.Drawings")
		(19 "Cmts.User" user "User.Comments")
		(21 "Eco1.User" user "User.Eco1")
		(23 "Eco2.User" user "User.Eco2")
		(25 "Edge.Cuts" user "Board Geometry/Outline")
		(27 "Margin" user)
		(31 "F.CrtYd" user "Package Geometry/Place Bound Top")
		(29 "B.CrtYd" user "Package Geometry/Place Bound Bottom")
		(35 "F.Fab" user "Ref Des/Assembly Top")
		(33 "B.Fab" user "Ref Des/Assembly Bottom")
	)
	(footprint ""
		(layer "B.Cu")
		(at 170.049952 -299.699934 -90)
		(property "Reference" "C1462"
			(at 0 0 90)
			(layer "B.SilkS")
			(hide yes)
			(effects
				(font
					(size 1.27 1.27)
				)
				(justify mirror)
			)
		)
		(property "Value" ""
			(at 0 0 90)
			(layer "B.Fab")
			(effects
				(font
					(size 1.27 1.27)
				)
				(justify mirror)
			)
		)
		(duplicate_pad_numbers_are_jumpers no)
		(fp_line
			(start -0.299974 0.150114)
			(end 0.299974 0.150114)
			(stroke
				(width 0.1)
				(type default)
			)
			(layer "B.Fab")
		)
		(fp_line
			(start 0.299974 0.150114)
			(end 0.299974 -0.150114)
			(stroke
				(width 0.1)
				(type default)
			)
			(layer "B.Fab")
		)
		(fp_line
			(start -0.299974 -0.150114)
			(end -0.299974 0.150114)
			(stroke
				(width 0.1)
				(type default)
			)
			(layer "B.Fab")
		)
		(fp_line
			(start 0.299974 -0.150114)
			(end -0.299974 -0.150114)
			(stroke
				(width 0.1)
				(type default)
			)
			(layer "B.Fab")
		)
		(pad "1" smd rect
			(at 0.2667 0 90)
			(size 0.3048 0.381)
			(layers "B.Cu" "B.Mask" "B.Paste")
			(net "P0V8_SERDES_VDDA_PEX1")
		)
		(pad "2" smd rect
			(at -0.2667 0 90)
			(size 0.3048 0.381)
			(layers "B.Cu" "B.Mask" "B.Paste")
			(net "GND")
		)
	)
	(footprint ""
		(layer "B.Cu")
		(at 239.470184 -222.292672 90)
		(property "Reference" "L148"
			(at 0 0 90)
			(layer "B.SilkS")
			(hide yes)
			(effects
				(font
					(size 1.27 1.27)
				)
				(justify mirror)
			)
		)
		(property "Value" ""
			(at 0 0 90)
			(layer "B.Fab")
			(effects
				(font
					(size 1.27 1.27)
				)
				(justify mirror)
			)
		)
		(duplicate_pad_numbers_are_jumpers no)
		(fp_line
			(start 1.27 -0.5842)
			(end -1.27 -0.5842)
			(stroke
				(width 0.1524)
				(type default)
			)
			(layer "B.SilkS")
		)
		(fp_line
			(start 1.27 -0.5588)
			(end 1.27 -0.5842)
			(stroke
				(width 0.1524)
				(type default)
			)
			(layer "B.SilkS")
		)
		(fp_line
			(start 1.27 0.5842)
			(end 1.27 -0.5842)
			(stroke
				(width 0.1524)
				(type default)
			)
			(layer "B.SilkS")
		)
		(fp_line
			(start -1.27 0.5842)
			(end -1.27 -0.5842)
			(stroke
				(width 0.1524)
				(type default)
			)
			(layer "B.SilkS")
		)
		(fp_line
			(start -1.27 0.5842)
			(end 1.27 0.5842)
			(stroke
				(width 0.1524)
				(type default)
			)
			(layer "B.SilkS")
		)
		(fp_line
			(start 0.9144 -0.508)
			(end -0.9144 -0.508)
			(stroke
				(width 0.1)
				(type default)
			)
			(layer "B.Fab")
		)
		(fp_line
			(start -0.9144 -0.508)
			(end -0.9144 -0.406654)
			(stroke
				(width 0.1)
				(type default)
			)
			(layer "B.Fab")
		)
		(fp_line
			(start 1.194308 -0.406654)
			(end 0.9144 -0.406654)
			(stroke
				(width 0.1)
				(type default)
			)
			(layer "B.Fab")
		)
		(fp_line
			(start 0.9144 -0.406654)
			(end 0.9144 -0.508)
			(stroke
				(width 0.1)
				(type default)
			)
			(layer "B.Fab")
		)
		(fp_line
			(start -0.9144 -0.406654)
			(end -1.1938 -0.406654)
			(stroke
				(width 0.1)
				(type default)
			)
			(layer "B.Fab")
		)
		(fp_line
			(start -1.1938 -0.406654)
			(end -1.1938 0.4064)
			(stroke
				(width 0.1)
				(type default)
			)
			(layer "B.Fab")
		)
		(fp_line
			(start -0.9144 0.4064)
			(end -0.9144 0.508)
			(stroke
				(width 0.1)
				(type default)
			)
			(layer "B.Fab")
		)
		(fp_line
			(start -1.1938 0.4064)
			(end -0.9144 0.4064)
			(stroke
				(width 0.1)
				(type default)
			)
			(layer "B.Fab")
		)
		(fp_line
			(start 1.194308 0.406654)
			(end 1.194308 -0.406654)
			(stroke
				(width 0.1)
				(type default)
			)
			(layer "B.Fab")
		)
		(fp_line
			(start 0.9144 0.406654)
			(end 1.194308 0.406654)
			(stroke
				(width 0.1)
				(type default)
			)
			(layer "B.Fab")
		)
		(fp_line
			(start 0.9144 0.508)
			(end 0.9144 0.406654)
			(stroke
				(width 0.1)
				(type default)
			)
			(layer "B.Fab")
		)
		(fp_line
			(start -0.9144 0.508)
			(end 0.9144 0.508)
			(stroke
				(width 0.1)
				(type default)
			)
			(layer "B.Fab")
		)
		(pad "1" smd rect
			(at 0.7366 0)
			(size 0.7112 0.8128)
			(layers "B.Cu" "B.Mask" "B.Paste")
			(net "P3V3_AUX")
		)
		(pad "2" smd rect
			(at -0.7366 0)
			(size 0.7112 0.8128)
			(layers "B.Cu" "B.Mask" "B.Paste")
			(net "P3V3_BIC_ADCAV33")
		)
	)
	(footprint ""
		(layer "B.Cu")
		(at 151.209248 -456.596496 180)
		(property "Reference" "X27"
			(at -4.300982 2.197862 90)
			(unlocked yes)
			(layer "B.SilkS")
			(effects
				(font
					(size 0.7874 0.5842)
					(thickness 0.1524)
				)
				(justify left mirror)
			)
		)
		(property "Value" ""
			(at 0 0 0)
			(layer "B.Fab")
			(effects
				(font
					(size 1.27 1.27)
				)
				(justify mirror)
			)
		)
		(property "Device Type" "TP_TDR_4P_FTS_MPKT4_H025P0200_IO_TP15_TP_TDR_4P_DIP"
			(at -1.30175 1.27 90)
			(unlocked yes)
			(layer "B.Fab")
			(hide yes)
			(effects
				(font
					(size 0.635 0.4064)
					(thickness 0.1524)
				)
				(justify mirror)
			)
		)
		(property "User Part Number" "TP15"
			(at -1.30175 1.27 90)
			(unlocked yes)
			(layer "Cmts.User")
			(hide yes)
			(effects
				(font
					(size 0.635 0.4064)
					(thickness 0.1524)
				)
				(justify mirror)
			)
		)
		(duplicate_pad_numbers_are_jumpers no)
		(fp_line
			(start 0 3.81)
			(end -2.54 3.81)
			(stroke
				(width 0.1524)
				(type default)
			)
			(layer "B.SilkS")
		)
		(fp_line
			(start 0 3.175)
			(end 0 3.81)
			(stroke
				(width 0.1524)
				(type default)
			)
			(layer "B.SilkS")
		)
		(fp_line
			(start 0 0.635)
			(end 0 1.905)
			(stroke
				(width 0.1524)
				(type default)
			)
			(layer "B.SilkS")
		)
		(fp_line
			(start 0 -1.27)
			(end 0 -0.635)
			(stroke
				(width 0.1524)
				(type default)
			)
			(layer "B.SilkS")
		)
		(fp_line
			(start -2.54 3.81)
			(end -2.54 3.6703)
			(stroke
				(width 0.1524)
				(type default)
			)
			(layer "B.SilkS")
		)
		(fp_line
			(start -2.54 1.4097)
			(end -2.54 1.1303)
			(stroke
				(width 0.1524)
				(type default)
			)
			(layer "B.SilkS")
		)
		(fp_line
			(start -2.54 -1.1303)
			(end -2.54 -1.27)
			(stroke
				(width 0.1524)
				(type default)
			)
			(layer "B.SilkS")
		)
		(fp_line
			(start -2.54 -1.27)
			(end 0 -1.27)
			(stroke
				(width 0.1524)
				(type default)
			)
			(layer "B.SilkS")
		)
		(fp_poly
			(pts
				(xy 0.761746 0) (xy 2.285746 -0.762) (xy 2.285746 0.762)
			)
			(stroke
				(width 0)
				(type default)
			)
			(fill yes)
			(layer "B.SilkS")
		)
		(fp_line
			(start 0 3.81)
			(end -2.54 3.81)
			(stroke
				(width 0.1)
				(type default)
			)
			(layer "B.Fab")
		)
		(fp_line
			(start 0 -1.27)
			(end 0 3.81)
			(stroke
				(width 0.1)
				(type default)
			)
			(layer "B.Fab")
		)
		(fp_line
			(start -2.54 3.81)
			(end -2.54 -1.27)
			(stroke
				(width 0.1)
				(type default)
			)
			(layer "B.Fab")
		)
		(fp_line
			(start -2.54 -1.27)
			(end 0 -1.27)
			(stroke
				(width 0.1)
				(type default)
			)
			(layer "B.Fab")
		)
		(fp_poly
			(pts
				(xy 0.761746 0) (xy 2.285746 -0.762) (xy 2.285746 0.762)
			)
			(stroke
				(width 0)
				(type default)
			)
			(fill yes)
			(layer "B.Fab")
		)
		(pad "1" thru_hole circle
			(at 0 0)
			(size 1.0033 1.0033)
			(drill 0.249936)
			(layers "*.Cu" "*.Mask")
			(remove_unused_layers no)
			(net "TDR_DIFF_85_IN4_DIN")
			(clearance 0.10795)
			(padstack
				(mode front_inner_back)
				(layer "Inner"
					(shape circle)
					(size 0.8001 0.8001)
					(clearance 0.1524)
				)
				(layer "B.Cu"
					(shape circle)
					(size 1.0033 1.0033)
					(thermal_gap 0.10795)
					(clearance 0.10795)
				)
			)
		)
		(pad "2" thru_hole circle
			(at -2.54 0)
			(size 1.9939 1.9939)
			(drill 0.249936)
			(layers "*.Cu" "*.Mask")
			(remove_unused_layers no)
			(net "COUPON_GND1")
			(clearance 0.10795)
			(padstack
				(mode front_inner_back)
				(layer "Inner"
					(shape circle)
					(size 0.8001 0.8001)
					(clearance 0.1524)
				)
				(layer "B.Cu"
					(shape circle)
					(size 1.9939 1.9939)
					(thermal_gap 0.10795)
					(clearance 0.10795)
				)
			)
		)
		(pad "3" thru_hole circle
			(at -2.54 2.54)
			(size 1.9939 1.9939)
			(drill 0.249936)
			(layers "*.Cu" "*.Mask")
			(remove_unused_layers no)
			(net "COUPON_GND1")
			(clearance 0.10795)
			(padstack
				(mode front_inner_back)
				(layer "Inner"
					(shape circle)
					(size 0.8001 0.8001)
					(clearance 0.1524)
				)
				(layer "B.Cu"
					(shape circle)
					(size 1.9939 1.9939)
					(thermal_gap 0.10795)
					(clearance 0.10795)
				)
			)
		)
		(pad "4" thru_hole circle
			(at 0 2.54)
			(size 1.0033 1.0033)
			(drill 0.249936)
			(layers "*.Cu" "*.Mask")
			(remove_unused_layers no)
			(net "TDR_DIFF_85_IN4_DIP")
			(clearance 0.10795)
			(padstack
				(mode front_inner_back)
				(layer "Inner"
					(shape circle)
					(size 0.8001 0.8001)
					(clearance 0.1524)
				)
				(layer "B.Cu"
					(shape circle)
					(size 1.0033 1.0033)
					(thermal_gap 0.10795)
					(clearance 0.10795)
				)
			)
		)
	)
	(footprint ""
		(layer "B.Cu")
		(at 403.164802 -140.931138 180)
		(property "Reference" "U38"
			(at -0.367792 1.820164 0)
			(unlocked yes)
			(layer "B.SilkS")
			(effects
				(font
					(size 0.7874 0.5842)
					(thickness 0.1524)
				)
				(justify mirror)
			)
		)
		(property "Value" ""
			(at 0 0 0)
			(layer "B.Fab")
			(effects
				(font
					(size 1.27 1.27)
				)
				(justify mirror)
			)
		)
		(duplicate_pad_numbers_are_jumpers no)
		(fp_line
			(start 1.3462 1.1938)
			(end -1.3462 1.1938)
			(stroke
				(width 0.1524)
				(type default)
			)
			(layer "B.SilkS")
		)
		(fp_line
			(start 1.3462 -1.1938)
			(end 1.3462 1.1684)
			(stroke
				(width 0.1524)
				(type default)
			)
			(layer "B.SilkS")
		)
		(fp_line
			(start -1.3462 1.1938)
			(end -1.3462 -1.1938)
			(stroke
				(width 0.1524)
				(type default)
			)
			(layer "B.SilkS")
		)
		(fp_line
			(start -1.3462 -1.1938)
			(end 1.3462 -1.1938)
			(stroke
				(width 0.1524)
				(type default)
			)
			(layer "B.SilkS")
		)
		(fp_poly
			(pts
				(xy 1.447038 -0.760476) (xy 2.052066 -0.457962) (xy 2.052066 -1.06299)
			)
			(stroke
				(width 0)
				(type default)
			)
			(fill yes)
			(layer "B.SilkS")
		)
		(fp_line
			(start 0.674878 1.124966)
			(end -0.674878 1.124966)
			(stroke
				(width 0.1)
				(type default)
			)
			(layer "B.Fab")
		)
		(fp_line
			(start 0.674878 -1.124966)
			(end 0.674878 1.124966)
			(stroke
				(width 0.1)
				(type default)
			)
			(layer "B.Fab")
		)
		(fp_line
			(start -0.674878 1.124966)
			(end -0.674878 -1.124966)
			(stroke
				(width 0.1)
				(type default)
			)
			(layer "B.Fab")
		)
		(fp_line
			(start -0.674878 -1.124966)
			(end 0.674878 -1.124966)
			(stroke
				(width 0.1)
				(type default)
			)
			(layer "B.Fab")
		)
		(fp_poly
			(pts
				(xy 1.447038 -0.760476) (xy 2.052066 -0.457962) (xy 2.052066 -1.06299)
			)
			(stroke
				(width 0)
				(type default)
			)
			(fill yes)
			(layer "B.Fab")
		)
		(pad "1" smd rect
			(at 0.899922 -0.750062)
			(size 0.6096 0.6096)
			(layers "B.Cu" "B.Mask" "B.Paste")
			(net "NIC6_AUX_PWR_EN_R")
		)
		(pad "2" smd rect
			(at 0.899922 0 270)
			(size 0.4064 0.6096)
			(layers "B.Cu" "B.Mask" "B.Paste")
			(net "RST_SMB_NIC6_MUX_N")
		)
		(pad "3" smd rect
			(at 0.899922 0.750062)
			(size 0.6096 0.6096)
			(layers "B.Cu" "B.Mask" "B.Paste")
			(net "GND")
		)
		(pad "4" smd rect
			(at -0.899922 0.750062)
			(size 0.6096 0.6096)
			(layers "B.Cu" "B.Mask" "B.Paste")
			(net "RST_SMB_NIC6_MUX_ISO_N")
		)
		(pad "5" smd rect
			(at -0.899922 -0.750062)
			(size 0.6096 0.6096)
			(layers "B.Cu" "B.Mask" "B.Paste")
			(net "P3V3_AUX")
		)
	)
	(footprint ""
		(layer "B.Cu")
		(at 206.112618 -232.58907)
		(property "Reference" "R6324"
			(at 0 0 0)
			(layer "B.SilkS")
			(hide yes)
			(effects
				(font
					(size 1.27 1.27)
				)
				(justify mirror)
			)
		)
		(property "Value" ""
			(at 0 0 0)
			(layer "B.Fab")
			(effects
				(font
					(size 1.27 1.27)
				)
				(justify mirror)
			)
		)
		(duplicate_pad_numbers_are_jumpers no)
		(fp_line
			(start -0.7874 -0.4064)
			(end -0.7874 0.4064)
			(stroke
				(width 0.1524)
				(type default)
			)
			(layer "B.SilkS")
		)
		(fp_line
			(start -0.7874 0.4064)
			(end 0.7874 0.4064)
			(stroke
				(width 0.1524)
				(type default)
			)
			(layer "B.SilkS")
		)
		(fp_line
			(start 0.7874 -0.4064)
			(end -0.7874 -0.4064)
			(stroke
				(width 0.1524)
				(type default)
			)
			(layer "B.SilkS")
		)
		(fp_line
			(start 0.7874 0.4064)
			(end 0.7874 -0.4064)
			(stroke
				(width 0.1524)
				(type default)
			)
			(layer "B.SilkS")
		)
		(fp_line
			(start -0.67945 -0.3048)
			(end -0.67945 0.3048)
			(stroke
				(width 0.1)
				(type default)
			)
			(layer "B.Fab")
		)
		(fp_line
			(start -0.67945 0.3048)
			(end -0.120396 0.3048)
			(stroke
				(width 0.1)
				(type default)
			)
			(layer "B.Fab")
		)
		(fp_line
			(start -0.12065 -0.3048)
			(end -0.67945 -0.3048)
			(stroke
				(width 0.1)
				(type default)
			)
			(layer "B.Fab")
		)
		(fp_line
			(start -0.12065 -0.2794)
			(end -0.12065 -0.3048)
			(stroke
				(width 0.1)
				(type default)
			)
			(layer "B.Fab")
		)
		(fp_line
			(start -0.120396 0.2794)
			(end 0.12065 0.2794)
			(stroke
				(width 0.1)
				(type default)
			)
			(layer "B.Fab")
		)
		(fp_line
			(start -0.120396 0.3048)
			(end -0.120396 0.2794)
			(stroke
				(width 0.1)
				(type default)
			)
			(layer "B.Fab")
		)
		(fp_line
			(start 0.12065 -0.305054)
			(end 0.12065 -0.2794)
			(stroke
				(width 0.1)
				(type default)
			)
			(layer "B.Fab")
		)
		(fp_line
			(start 0.12065 -0.2794)
			(end -0.12065 -0.2794)
			(stroke
				(width 0.1)
				(type default)
			)
			(layer "B.Fab")
		)
		(fp_line
			(start 0.12065 0.2794)
			(end 0.12065 0.3048)
			(stroke
				(width 0.1)
				(type default)
			)
			(layer "B.Fab")
		)
		(fp_line
			(start 0.12065 0.3048)
			(end 0.67945 0.3048)
			(stroke
				(width 0.1)
				(type default)
			)
			(layer "B.Fab")
		)
		(fp_line
			(start 0.67945 -0.305054)
			(end 0.12065 -0.305054)
			(stroke
				(width 0.1)
				(type default)
			)
			(layer "B.Fab")
		)
		(fp_line
			(start 0.67945 0.3048)
			(end 0.67945 -0.305054)
			(stroke
				(width 0.1)
				(type default)
			)
			(layer "B.Fab")
		)
		(pad "1" smd circle
			(at 0.40005 0 180)
			(size 0 0)
			(layers "B.Cu" "B.Mask" "B.Paste")
			(net "SMB_PEX1_SDA")
		)
		(pad "2" smd circle
			(at -0.40005 0 180)
			(size 0 0)
			(layers "B.Cu" "B.Mask" "B.Paste")
			(net "SMB_PEX1_MUX_SDA")
		)
	)
	(footprint ""
		(layer "B.Cu")
		(at 179.07508 -293.99992 90)
		(property "Reference" "C1385"
			(at 0 0 90)
			(layer "B.SilkS")
			(hide yes)
			(effects
				(font
					(size 1.27 1.27)
				)
				(justify mirror)
			)
		)
		(property "Value" ""
			(at 0 0 90)
			(layer "B.Fab")
			(effects
				(font
					(size 1.27 1.27)
				)
				(justify mirror)
			)
		)
		(duplicate_pad_numbers_are_jumpers no)
		(fp_line
			(start 0.299974 -0.150114)
			(end -0.299974 -0.150114)
			(stroke
				(width 0.1)
				(type default)
			)
			(layer "B.Fab")
		)
		(fp_line
			(start -0.299974 -0.150114)
			(end -0.299974 0.150114)
			(stroke
				(width 0.1)
				(type default)
			)
			(layer "B.Fab")
		)
		(fp_line
			(start 0.299974 0.150114)
			(end 0.299974 -0.150114)
			(stroke
				(width 0.1)
				(type default)
			)
			(layer "B.Fab")
		)
		(fp_line
			(start -0.299974 0.150114)
			(end 0.299974 0.150114)
			(stroke
				(width 0.1)
				(type default)
			)
			(layer "B.Fab")
		)
		(pad "1" smd rect
			(at 0.2667 0 270)
			(size 0.3048 0.381)
			(layers "B.Cu" "B.Mask" "B.Paste")
			(net "P0V8_PEX1")
		)
		(pad "2" smd rect
			(at -0.2667 0 270)
			(size 0.3048 0.381)
			(layers "B.Cu" "B.Mask" "B.Paste")
			(net "GND")
		)
	)
	(footprint ""
		(layer "B.Cu")
		(at 112.583976 -277.644352 180)
		(property "Reference" "PC6609"
			(at 0 0 0)
			(layer "B.SilkS")
			(hide yes)
			(effects
				(font
					(size 1.27 1.27)
				)
				(justify mirror)
			)
		)
		(property "Value" ""
			(at 0 0 0)
			(layer "B.Fab")
			(effects
				(font
					(size 1.27 1.27)
				)
				(justify mirror)
			)
		)
		(duplicate_pad_numbers_are_jumpers no)
		(fp_line
			(start 1.524 0.762)
			(end 1.524 -0.762)
			(stroke
				(width 0.1524)
				(type default)
			)
			(layer "B.SilkS")
		)
		(fp_line
			(start 1.524 -0.762)
			(end -1.524 -0.762)
			(stroke
				(width 0.1524)
				(type default)
			)
			(layer "B.SilkS")
		)
		(fp_line
			(start -1.524 0.762)
			(end 1.524 0.762)
			(stroke
				(width 0.1524)
				(type default)
			)
			(layer "B.SilkS")
		)
		(fp_line
			(start -1.524 -0.762)
			(end -1.524 0.762)
			(stroke
				(width 0.1524)
				(type default)
			)
			(layer "B.SilkS")
		)
		(fp_line
			(start 1.1049 0.724916)
			(end -1.1049 0.724916)
			(stroke
				(width 0.1)
				(type default)
			)
			(layer "B.Fab")
		)
		(fp_line
			(start 1.1049 -0.724916)
			(end 1.1049 0.724916)
			(stroke
				(width 0.1)
				(type default)
			)
			(layer "B.Fab")
		)
		(fp_line
			(start -1.1049 0.724916)
			(end -1.1049 -0.724916)
			(stroke
				(width 0.1)
				(type default)
			)
			(layer "B.Fab")
		)
		(fp_line
			(start -1.1049 -0.724916)
			(end 1.1049 -0.724916)
			(stroke
				(width 0.1)
				(type default)
			)
			(layer "B.Fab")
		)
		(pad "1" smd rect
			(at 0.889 0 180)
			(size 1.016 1.27)
			(layers "B.Cu" "B.Mask" "B.Paste")
			(net "SW_P12V_P0V8_PEX0_FLT")
		)
		(pad "2" smd rect
			(at -0.889 0 180)
			(size 1.016 1.27)
			(layers "B.Cu" "B.Mask" "B.Paste")
			(net "GND")
		)
	)
)
